(kicad_pcb
	(version 20260206)
	(generator "pcbnew")
	(generator_version "10.0")
	(general
		(thickness 1.6)
		(legacy_teardrops no)
	)
	(paper "A4")
	(title_block
		(title "baseboard — 13948-1b.1110WZS1818.brd")
		(comment 1 "Honey Badger (Wiwynn) / footprint 480 of 2523 (CN2), pads 1-44 of 44")
	)
	(layers
		(0 "F.Cu" signal "TOP")
		(4 "In1.Cu" signal "L2GND")
		(6 "In2.Cu" signal "L3")
		(8 "In3.Cu" signal "L4VCC")
		(10 "In4.Cu" signal "L5VCC")
		(12 "In5.Cu" signal "L6")
		(14 "In6.Cu" signal "L7GND")
		(2 "B.Cu" signal "BOTTOM")
		(9 "F.Adhes" user "F.Adhesive")
		(11 "B.Adhes" user "B.Adhesive")
		(13 "F.Paste" user "Package Geometry/Pastemask Top")
		(15 "B.Paste" user "Package Geometry/Pastemask Bottom")
		(5 "F.SilkS" user "Ref Des/Silkscreen Top")
		(7 "B.SilkS" user "Ref Des/Silkscreen Bottom")
		(1 "F.Mask" user "Board Geometry/Soldermask Top")
		(3 "B.Mask" user "Board Geometry/Soldermask Bottom")
		(17 "Dwgs.User" user "User.Drawings")
		(19 "Cmts.User" user "User.Comments")
		(21 "Eco1.User" user "User.Eco1")
		(23 "Eco2.User" user "User.Eco2")
		(25 "Edge.Cuts" user "Board Geometry/Outline")
		(27 "Margin" user)
		(31 "F.CrtYd" user "Package Geometry/Place Bound Top")
		(29 "B.CrtYd" user "Package Geometry/Place Bound Bottom")
		(35 "F.Fab" user "Ref Des/Assembly Top")
		(33 "B.Fab" user "Ref Des/Assembly Bottom")
	)
	(footprint ""
		(layer "F.Cu")
		(at 47.999904 -71.900034)
		(property "Reference" "CN2"
			(at 0 0 0)
			(layer "F.SilkS")
			(hide yes)
			(effects
				(font
					(size 1.27 1.27)
				)
			)
		)
		(property "Value" "AMP-CONN36-2R-GP"
			(at -10.922 -7.0612 0)
			(unlocked yes)
			(layer "F.Fab")
			(hide yes)
			(effects
				(font
					(size 1.016 1.016)
					(thickness 0.1524)
				)
			)
		)
		(property "Device Type" "G40MR36U11AEU"
			(at -10.922 -8.5852 0)
			(unlocked yes)
			(layer "F.Fab")
			(hide yes)
			(effects
				(font
					(size 1.016 1.016)
					(thickness 0.1524)
				)
			)
		)
		(duplicate_pad_numbers_are_jumpers no)
		(pad "" np_thru_hole circle
			(at -7.999984 0)
			(size 0.254 0.254)
			(drill 1.5748)
			(layers "*.Cu" "*.Mask")
			(clearance 1.016)
			(thermal_gap 1.016)
		)
		(pad "" np_thru_hole circle
			(at 7.999984 0)
			(size 0.254 0.254)
			(drill 1.5748)
			(layers "*.Cu" "*.Mask")
			(clearance 1.016)
			(thermal_gap 1.016)
		)
		(pad "37" thru_hole circle
			(at -8.899906 5.72008)
			(size 1.1684 1.1684)
			(drill 0.8128)
			(layers "*.Cu" "*.Mask")
			(remove_unused_layers no)
			(net "GND")
			(clearance 0.1778)
			(thermal_gap 0.1778)
		)
		(pad "38" thru_hole circle
			(at -8.899906 9.219946)
			(size 1.1684 1.1684)
			(drill 0.8128)
			(layers "*.Cu" "*.Mask")
			(remove_unused_layers no)
			(net "GND")
			(clearance 0.1778)
			(thermal_gap 0.1778)
		)
		(pad "39" thru_hole circle
			(at -8.899906 11.219942)
			(size 1.1684 1.1684)
			(drill 0.8128)
			(layers "*.Cu" "*.Mask")
			(remove_unused_layers no)
			(net "GND")
			(clearance 0.1778)
			(thermal_gap 0.1778)
		)
		(pad "40" thru_hole circle
			(at 8.899906 12.21994)
			(size 1.1684 1.1684)
			(drill 0.8128)
			(layers "*.Cu" "*.Mask")
			(remove_unused_layers no)
			(net "GND")
			(clearance 0.1778)
			(thermal_gap 0.1778)
		)
		(pad "41" thru_hole circle
			(at 8.899906 9.219946)
			(size 1.1684 1.1684)
			(drill 0.8128)
			(layers "*.Cu" "*.Mask")
			(remove_unused_layers no)
			(net "GND")
			(clearance 0.1778)
			(thermal_gap 0.1778)
		)
		(pad "42" thru_hole circle
			(at 8.899906 5.72008)
			(size 1.1684 1.1684)
			(drill 0.8128)
			(layers "*.Cu" "*.Mask")
			(remove_unused_layers no)
			(net "GND")
			(clearance 0.1778)
			(thermal_gap 0.1778)
		)
		(pad "A1" smd oval
			(at -6.599936 -5.180076)
			(size 0.3556 1.8034)
			(layers "F.Cu" "F.Mask" "F.Paste")
			(net "GND")
		)
		(pad "A2" smd oval
			(at -5.80009 -5.180076)
			(size 0.3556 1.8034)
			(layers "F.Cu" "F.Mask" "F.Paste")
			(net "MINI_RX_P_20")
		)
		(pad "A3" smd oval
			(at -4.99999 -5.180076)
			(size 0.3556 1.8034)
			(layers "F.Cu" "F.Mask" "F.Paste")
			(net "MINI_RX_N_20")
		)
		(pad "A4" smd oval
			(at -4.19989 -5.180076)
			(size 0.3556 1.8034)
			(layers "F.Cu" "F.Mask" "F.Paste")
			(net "GND")
		)
		(pad "A5" smd oval
			(at -3.400044 -5.180076)
			(size 0.3556 1.8034)
			(layers "F.Cu" "F.Mask" "F.Paste")
			(net "MINI_RX_P_21")
		)
		(pad "A6" smd oval
			(at -2.599944 -5.180076)
			(size 0.3556 1.8034)
			(layers "F.Cu" "F.Mask" "F.Paste")
			(net "MINI_RX_N_21")
		)
		(pad "A7" smd oval
			(at -1.800098 -5.180076)
			(size 0.3556 1.8034)
			(layers "F.Cu" "F.Mask" "F.Paste")
			(net "GND")
		)
		(pad "A8" smd oval
			(at -0.999998 -5.180076)
			(size 0.3556 1.8034)
			(layers "F.Cu" "F.Mask" "F.Paste")
			(net "INT_CONN_A_SB7")
		)
		(pad "A9" smd oval
			(at -0.199898 -5.180076)
			(size 0.3556 1.8034)
			(layers "F.Cu" "F.Mask" "F.Paste")
			(net "INT_CONN_A_SB3")
		)
		(pad "A10" smd oval
			(at 0.599948 -5.180076)
			(size 0.3556 1.8034)
			(layers "F.Cu" "F.Mask" "F.Paste")
			(net "INT_CONN_A_SB4")
		)
		(pad "A11" smd oval
			(at 1.400048 -5.180076)
			(size 0.3556 1.8034)
			(layers "F.Cu" "F.Mask" "F.Paste")
			(net "INT_CONN_A_SB5")
		)
		(pad "A12" smd oval
			(at 2.199894 -5.180076)
			(size 0.3556 1.8034)
			(layers "F.Cu" "F.Mask" "F.Paste")
			(net "GND")
		)
		(pad "A13" smd oval
			(at 2.999994 -5.180076)
			(size 0.3556 1.8034)
			(layers "F.Cu" "F.Mask" "F.Paste")
			(net "MINI_RX_P_22")
		)
		(pad "A14" smd oval
			(at 3.800094 -5.180076)
			(size 0.3556 1.8034)
			(layers "F.Cu" "F.Mask" "F.Paste")
			(net "MINI_RX_N_22")
		)
		(pad "A15" smd oval
			(at 4.59994 -5.180076)
			(size 0.3556 1.8034)
			(layers "F.Cu" "F.Mask" "F.Paste")
			(net "GND")
		)
		(pad "A16" smd oval
			(at 5.40004 -5.180076)
			(size 0.3556 1.8034)
			(layers "F.Cu" "F.Mask" "F.Paste")
			(net "MINI_RX_P_23")
		)
		(pad "A17" smd oval
			(at 6.199886 -5.180076)
			(size 0.3556 1.8034)
			(layers "F.Cu" "F.Mask" "F.Paste")
			(net "MINI_RX_N_23")
		)
		(pad "A18" smd oval
			(at 6.999986 -5.180076)
			(size 0.3556 1.8034)
			(layers "F.Cu" "F.Mask" "F.Paste")
			(net "GND")
		)
		(pad "B1" smd oval
			(at -6.999986 -7.690104)
			(size 0.3556 1.8034)
			(layers "F.Cu" "F.Mask" "F.Paste")
			(net "GND")
		)
		(pad "B2" smd oval
			(at -6.199886 -7.690104)
			(size 0.3556 1.8034)
			(layers "F.Cu" "F.Mask" "F.Paste")
			(net "SAS_EXP2CONN_TX_P_20")
		)
		(pad "B3" smd oval
			(at -5.40004 -7.690104)
			(size 0.3556 1.8034)
			(layers "F.Cu" "F.Mask" "F.Paste")
			(net "SAS_EXP2CONN_TX_N_20")
		)
		(pad "B4" smd oval
			(at -4.59994 -7.690104)
			(size 0.3556 1.8034)
			(layers "F.Cu" "F.Mask" "F.Paste")
			(net "GND")
		)
		(pad "B5" smd oval
			(at -3.800094 -7.690104)
			(size 0.3556 1.8034)
			(layers "F.Cu" "F.Mask" "F.Paste")
			(net "SAS_EXP2CONN_TX_P_21")
		)
		(pad "B6" smd oval
			(at -2.999994 -7.690104)
			(size 0.3556 1.8034)
			(layers "F.Cu" "F.Mask" "F.Paste")
			(net "SAS_EXP2CONN_TX_N_21")
		)
		(pad "B7" smd oval
			(at -2.199894 -7.690104)
			(size 0.3556 1.8034)
			(layers "F.Cu" "F.Mask" "F.Paste")
			(net "GND")
		)
		(pad "B8" smd oval
			(at -1.400048 -7.690104)
			(size 0.3556 1.8034)
			(layers "F.Cu" "F.Mask" "F.Paste")
			(net "INT_CONN_A_SB0")
		)
		(pad "B9" smd oval
			(at -0.599948 -7.690104)
			(size 0.3556 1.8034)
			(layers "F.Cu" "F.Mask" "F.Paste")
			(net "INT_CONN_A_SB1")
		)
		(pad "B10" smd oval
			(at 0.199898 -7.690104)
			(size 0.3556 1.8034)
			(layers "F.Cu" "F.Mask" "F.Paste")
			(net "INT_CONN_A_SB2")
		)
		(pad "B11" smd oval
			(at 0.999998 -7.690104)
			(size 0.3556 1.8034)
			(layers "F.Cu" "F.Mask" "F.Paste")
			(net "INT_CONN_A_SB6")
		)
		(pad "B12" smd oval
			(at 1.800098 -7.690104)
			(size 0.3556 1.8034)
			(layers "F.Cu" "F.Mask" "F.Paste")
			(net "GND")
		)
		(pad "B13" smd oval
			(at 2.599944 -7.690104)
			(size 0.3556 1.8034)
			(layers "F.Cu" "F.Mask" "F.Paste")
			(net "SAS_EXP2CONN_TX_P_22")
		)
		(pad "B14" smd oval
			(at 3.400044 -7.690104)
			(size 0.3556 1.8034)
			(layers "F.Cu" "F.Mask" "F.Paste")
			(net "SAS_EXP2CONN_TX_N_22")
		)
		(pad "B15" smd oval
			(at 4.19989 -7.690104)
			(size 0.3556 1.8034)
			(layers "F.Cu" "F.Mask" "F.Paste")
			(net "GND")
		)
		(pad "B16" smd oval
			(at 4.99999 -7.690104)
			(size 0.3556 1.8034)
			(layers "F.Cu" "F.Mask" "F.Paste")
			(net "SAS_EXP2CONN_TX_P_23")
		)
		(pad "B17" smd oval
			(at 5.80009 -7.690104)
			(size 0.3556 1.8034)
			(layers "F.Cu" "F.Mask" "F.Paste")
			(net "SAS_EXP2CONN_TX_N_23")
		)
		(pad "B18" smd oval
			(at 6.599936 -7.690104)
			(size 0.3556 1.8034)
			(layers "F.Cu" "F.Mask" "F.Paste")
			(net "GND")
		)
	)
)
